(kicad_pcb
	(version 20260206)
	(generator "pcbnew")
	(generator_version "10.0")
	(general
		(thickness 1.6)
		(legacy_teardrops no)
	)
	(paper "A4")
	(title_block
		(title "v2-pdb — ms_pdb_v2.brd")
		(comment 1 "Open CloudServer (Microsoft) / footprints 15-23 of 348")
	)
	(layers
		(0 "F.Cu" signal "TOP")
		(4 "In1.Cu" signal "GND")
		(6 "In2.Cu" signal "IN1")
		(8 "In3.Cu" signal "VCC")
		(10 "In4.Cu" signal "VCC1")
		(12 "In5.Cu" signal "IN2")
		(14 "In6.Cu" signal "GND1")
		(2 "B.Cu" signal "BOTTOM")
		(9 "F.Adhes" user "F.Adhesive")
		(11 "B.Adhes" user "B.Adhesive")
		(13 "F.Paste" user "Package Geometry/Pastemask Top")
		(15 "B.Paste" user "Package Geometry/Pastemask Bottom")
		(5 "F.SilkS" user "Ref Des/Silkscreen Top")
		(7 "B.SilkS" user "Ref Des/Silkscreen Bottom")
		(1 "F.Mask" user "Board Geometry/Soldermask Top")
		(3 "B.Mask" user "Board Geometry/Soldermask Bottom")
		(17 "Dwgs.User" user "User.Drawings")
		(19 "Cmts.User" user "User.Comments")
		(21 "Eco1.User" user "User.Eco1")
		(23 "Eco2.User" user "User.Eco2")
		(25 "Edge.Cuts" user "Board Geometry/Outline")
		(27 "Margin" user)
		(31 "F.CrtYd" user "Package Geometry/Place Bound Top")
		(29 "B.CrtYd" user "Package Geometry/Place Bound Bottom")
		(35 "F.Fab" user "Ref Des/Assembly Top")
		(33 "B.Fab" user "Ref Des/Assembly Bottom")
	)
	(footprint ""
		(layer "F.Cu")
		(at 50.150268 -350.765364 180)
		(property "Reference" "CE16"
			(at -4.708906 1.983994 0)
			(unlocked yes)
			(layer "F.SilkS")
			(effects
				(font
					(size 0.7874 0.5842)
					(thickness 0.1524)
				)
				(justify left)
			)
		)
		(property "Value" ""
			(at 0 0 180)
			(layer "F.Fab")
			(effects
				(font
					(size 1.27 1.27)
				)
			)
		)
		(duplicate_pad_numbers_are_jumpers no)
		(fp_line
			(start 0 -4.2672)
			(end 0 4.2672)
			(stroke
				(width 0.1524)
				(type default)
			)
			(layer "F.SilkS")
		)
		(fp_circle
			(center 0 0)
			(end -4.2672 0)
			(stroke
				(width 0.1524)
				(type default)
			)
			(fill no)
			(layer "F.SilkS")
		)
		(fp_poly
			(pts
				(arc
					(start 0 -4.2672)
					(mid 4.2672 0)
					(end 0 4.2672)
				)
			)
			(stroke
				(width 0)
				(type default)
			)
			(fill yes)
			(layer "F.SilkS")
		)
		(fp_poly
			(pts
				(xy -2.5146 -0.762) (xy -0.9906 -0.762) (xy -0.9906 0.762) (xy -2.5146 0.762)
			)
			(stroke
				(width 0)
				(type default)
			)
			(fill no)
			(layer "B.CrtYd")
		)
		(fp_poly
			(pts
				(arc
					(start 1.7526 0.762)
					(mid 2.291415 -0.538815)
					(end 0.9906 0)
				)
				(arc
					(start 0.9906 0.0254)
					(mid 1.206345 0.546255)
					(end 1.7272 0.762)
				)
			)
			(stroke
				(width 0)
				(type default)
			)
			(fill no)
			(layer "B.CrtYd")
		)
		(fp_poly
			(pts
				(arc
					(start -4.2672 0)
					(mid 4.2672 0)
					(end -4.2672 0)
				)
			)
			(stroke
				(width 0)
				(type default)
			)
			(fill no)
			(layer "F.CrtYd")
		)
		(fp_circle
			(center 0 0)
			(end -4.2672 0)
			(stroke
				(width 0.1)
				(type default)
			)
			(fill no)
			(layer "F.Fab")
		)
		(fp_text user "+"
			(at -5.759196 -0.592582 180)
			(unlocked yes)
			(layer "F.SilkS")
			(effects
				(font
					(size 1.905 1.4224)
					(thickness 0.1524)
				)
				(justify left)
			)
		)
		(fp_text user "+"
			(at -5.6642 -0.34925 180)
			(unlocked yes)
			(layer "F.Fab")
			(effects
				(font
					(size 1.905 1.4224)
					(thickness 0.000001)
				)
				(justify left)
			)
		)
		(pad "1" thru_hole rect
			(at -1.75006 0 180)
			(size 1.397 1.397)
			(drill 0.9144)
			(layers "*.Cu" "*.Mask")
			(remove_unused_layers no)
			(net "P12V")
			(clearance 0.0127)
			(thermal_gap 0.0127)
			(padstack
				(mode front_inner_back)
				(layer "Inner"
					(shape circle)
					(size 1.397 1.397)
					(clearance 0.0127)
				)
				(layer "B.Cu"
					(shape rect)
					(size 1.397 1.397)
					(clearance 0.0127)
				)
			)
		)
		(pad "2" thru_hole circle
			(at 1.75006 0 180)
			(size 1.397 1.397)
			(drill 0.9144)
			(layers "*.Cu" "*.Mask")
			(remove_unused_layers no)
			(net "GND")
			(clearance 0.0127)
			(thermal_gap 0.0127)
		)
	)
	(footprint ""
		(layer "F.Cu")
		(at 26.068274 -184.266078)
		(property "Reference" "R72"
			(at -3.997198 0.128524 0)
			(unlocked yes)
			(layer "F.SilkS")
			(effects
				(font
					(size 0.7874 0.5842)
					(thickness 0.1524)
				)
				(justify left)
			)
		)
		(property "Value" ""
			(at 0 0 0)
			(layer "F.Fab")
			(effects
				(font
					(size 1.27 1.27)
				)
			)
		)
		(duplicate_pad_numbers_are_jumpers no)
		(fp_line
			(start -0.7874 -0.4064)
			(end 0.7874 -0.4064)
			(stroke
				(width 0.1524)
				(type default)
			)
			(layer "F.SilkS")
		)
		(fp_line
			(start -0.7874 0.4064)
			(end -0.7874 -0.4064)
			(stroke
				(width 0.1524)
				(type default)
			)
			(layer "F.SilkS")
		)
		(fp_line
			(start 0.7874 -0.4064)
			(end 0.7874 0.4064)
			(stroke
				(width 0.1524)
				(type default)
			)
			(layer "F.SilkS")
		)
		(fp_line
			(start 0.7874 0.4064)
			(end -0.7874 0.4064)
			(stroke
				(width 0.1524)
				(type default)
			)
			(layer "F.SilkS")
		)
		(fp_poly
			(pts
				(xy -0.508 0.2794) (xy -0.508 0.2286) (xy -0.635 0.2286) (xy -0.635 -0.254) (xy -0.5334 -0.254)
				(xy -0.5334 -0.2794) (xy 0.5334 -0.2794) (xy 0.5334 -0.254) (xy 0.635 -0.254) (xy 0.635 0.254) (xy 0.5334 0.254)
				(xy 0.5334 0.2794)
			)
			(stroke
				(width 0)
				(type default)
			)
			(fill no)
			(layer "F.CrtYd")
		)
		(pad "1" smd rect
			(at 0.40005 0)
			(size 0.4572 0.508)
			(layers "F.Cu" "F.Mask" "F.Paste")
			(net "PSU3_RESET")
		)
		(pad "2" smd rect
			(at -0.40005 0)
			(size 0.4572 0.508)
			(layers "F.Cu" "F.Mask" "F.Paste")
			(net "P12V_STBY")
		)
	)
	(footprint ""
		(layer "F.Cu")
		(at 50.478944 -329.972416 180)
		(property "Reference" "CE15"
			(at 1.661922 5.89026 0)
			(unlocked yes)
			(layer "F.SilkS")
			(effects
				(font
					(size 0.7874 0.5842)
					(thickness 0.1524)
				)
				(justify left)
			)
		)
		(property "Value" ""
			(at 0 0 180)
			(layer "F.Fab")
			(effects
				(font
					(size 1.27 1.27)
				)
			)
		)
		(duplicate_pad_numbers_are_jumpers no)
		(fp_line
			(start 0 -4.2672)
			(end 0 4.2672)
			(stroke
				(width 0.1524)
				(type default)
			)
			(layer "F.SilkS")
		)
		(fp_circle
			(center 0 0)
			(end -4.2672 0)
			(stroke
				(width 0.1524)
				(type default)
			)
			(fill no)
			(layer "F.SilkS")
		)
		(fp_poly
			(pts
				(arc
					(start 0 -4.2672)
					(mid 4.2672 0)
					(end 0 4.2672)
				)
			)
			(stroke
				(width 0)
				(type default)
			)
			(fill yes)
			(layer "F.SilkS")
		)
		(fp_poly
			(pts
				(xy -2.5146 -0.762) (xy -0.9906 -0.762) (xy -0.9906 0.762) (xy -2.5146 0.762)
			)
			(stroke
				(width 0)
				(type default)
			)
			(fill no)
			(layer "B.CrtYd")
		)
		(fp_poly
			(pts
				(arc
					(start 1.7526 0.762)
					(mid 2.291415 -0.538815)
					(end 0.9906 0)
				)
				(arc
					(start 0.9906 0.0254)
					(mid 1.206345 0.546255)
					(end 1.7272 0.762)
				)
			)
			(stroke
				(width 0)
				(type default)
			)
			(fill no)
			(layer "B.CrtYd")
		)
		(fp_poly
			(pts
				(arc
					(start -4.2672 0)
					(mid 4.2672 0)
					(end -4.2672 0)
				)
			)
			(stroke
				(width 0)
				(type default)
			)
			(fill no)
			(layer "F.CrtYd")
		)
		(fp_circle
			(center 0 0)
			(end -4.2672 0)
			(stroke
				(width 0.1)
				(type default)
			)
			(fill no)
			(layer "F.Fab")
		)
		(fp_text user "+"
			(at -5.60578 -0.450596 180)
			(unlocked yes)
			(layer "F.SilkS")
			(effects
				(font
					(size 1.905 1.4224)
					(thickness 0.1524)
				)
				(justify left)
			)
		)
		(fp_text user "+"
			(at -5.6642 -0.34925 180)
			(unlocked yes)
			(layer "F.Fab")
			(effects
				(font
					(size 1.905 1.4224)
					(thickness 0.000001)
				)
				(justify left)
			)
		)
		(pad "1" thru_hole rect
			(at -1.75006 0 180)
			(size 1.397 1.397)
			(drill 0.9144)
			(layers "*.Cu" "*.Mask")
			(remove_unused_layers no)
			(net "P12V")
			(clearance 0.0127)
			(thermal_gap 0.0127)
			(padstack
				(mode front_inner_back)
				(layer "Inner"
					(shape circle)
					(size 1.397 1.397)
					(clearance 0.0127)
				)
				(layer "B.Cu"
					(shape rect)
					(size 1.397 1.397)
					(clearance 0.0127)
				)
			)
		)
		(pad "2" thru_hole circle
			(at 1.75006 0 180)
			(size 1.397 1.397)
			(drill 0.9144)
			(layers "*.Cu" "*.Mask")
			(remove_unused_layers no)
			(net "GND")
			(clearance 0.0127)
			(thermal_gap 0.0127)
		)
	)
	(footprint ""
		(layer "F.Cu")
		(at 50.32756 -285.205424 180)
		(property "Reference" "CE13"
			(at -4.667758 1.872742 0)
			(unlocked yes)
			(layer "F.SilkS")
			(effects
				(font
					(size 0.7874 0.5842)
					(thickness 0.1524)
				)
				(justify left)
			)
		)
		(property "Value" ""
			(at 0 0 180)
			(layer "F.Fab")
			(effects
				(font
					(size 1.27 1.27)
				)
			)
		)
		(duplicate_pad_numbers_are_jumpers no)
		(fp_line
			(start 0 -4.2672)
			(end 0 4.2672)
			(stroke
				(width 0.1524)
				(type default)
			)
			(layer "F.SilkS")
		)
		(fp_circle
			(center 0 0)
			(end -4.2672 0)
			(stroke
				(width 0.1524)
				(type default)
			)
			(fill no)
			(layer "F.SilkS")
		)
		(fp_poly
			(pts
				(arc
					(start 0 -4.2672)
					(mid 4.2672 0)
					(end 0 4.2672)
				)
			)
			(stroke
				(width 0)
				(type default)
			)
			(fill yes)
			(layer "F.SilkS")
		)
		(fp_poly
			(pts
				(xy -2.5146 -0.762) (xy -0.9906 -0.762) (xy -0.9906 0.762) (xy -2.5146 0.762)
			)
			(stroke
				(width 0)
				(type default)
			)
			(fill no)
			(layer "B.CrtYd")
		)
		(fp_poly
			(pts
				(arc
					(start 1.7526 0.762)
					(mid 2.291415 -0.538815)
					(end 0.9906 0)
				)
				(arc
					(start 0.9906 0.0254)
					(mid 1.206345 0.546255)
					(end 1.7272 0.762)
				)
			)
			(stroke
				(width 0)
				(type default)
			)
			(fill no)
			(layer "B.CrtYd")
		)
		(fp_poly
			(pts
				(arc
					(start -4.2672 0)
					(mid 4.2672 0)
					(end -4.2672 0)
				)
			)
			(stroke
				(width 0)
				(type default)
			)
			(fill no)
			(layer "F.CrtYd")
		)
		(fp_circle
			(center 0 0)
			(end -4.2672 0)
			(stroke
				(width 0.1)
				(type default)
			)
			(fill no)
			(layer "F.Fab")
		)
		(fp_text user "+"
			(at -5.6642 -0.34925 180)
			(unlocked yes)
			(layer "F.SilkS")
			(effects
				(font
					(size 1.905 1.4224)
					(thickness 0.1524)
				)
				(justify left)
			)
		)
		(fp_text user "+"
			(at -5.6642 -0.34925 180)
			(unlocked yes)
			(layer "F.Fab")
			(effects
				(font
					(size 1.905 1.4224)
					(thickness 0.000001)
				)
				(justify left)
			)
		)
		(pad "1" thru_hole rect
			(at -1.75006 0 180)
			(size 1.397 1.397)
			(drill 0.9144)
			(layers "*.Cu" "*.Mask")
			(remove_unused_layers no)
			(net "P12V")
			(clearance 0.0127)
			(thermal_gap 0.0127)
			(padstack
				(mode front_inner_back)
				(layer "Inner"
					(shape circle)
					(size 1.397 1.397)
					(clearance 0.0127)
				)
				(layer "B.Cu"
					(shape rect)
					(size 1.397 1.397)
					(clearance 0.0127)
				)
			)
		)
		(pad "2" thru_hole circle
			(at 1.75006 0 180)
			(size 1.397 1.397)
			(drill 0.9144)
			(layers "*.Cu" "*.Mask")
			(remove_unused_layers no)
			(net "GND")
			(clearance 0.0127)
			(thermal_gap 0.0127)
		)
	)
	(footprint ""
		(layer "F.Cu")
		(at 26.25217 -454.646538 180)
		(property "Reference" "R54"
			(at 3.629406 0.859536 0)
			(unlocked yes)
			(layer "F.SilkS")
			(effects
				(font
					(size 0.7874 0.5842)
					(thickness 0.1524)
				)
				(justify left)
			)
		)
		(property "Value" ""
			(at 0 0 180)
			(layer "F.Fab")
			(effects
				(font
					(size 1.27 1.27)
				)
			)
		)
		(duplicate_pad_numbers_are_jumpers no)
		(fp_line
			(start 0.7874 0.4064)
			(end -0.7874 0.4064)
			(stroke
				(width 0.1524)
				(type default)
			)
			(layer "F.SilkS")
		)
		(fp_line
			(start 0.7874 -0.4064)
			(end 0.7874 0.4064)
			(stroke
				(width 0.1524)
				(type default)
			)
			(layer "F.SilkS")
		)
		(fp_line
			(start -0.7874 0.4064)
			(end -0.7874 -0.4064)
			(stroke
				(width 0.1524)
				(type default)
			)
			(layer "F.SilkS")
		)
		(fp_line
			(start -0.7874 -0.4064)
			(end 0.7874 -0.4064)
			(stroke
				(width 0.1524)
				(type default)
			)
			(layer "F.SilkS")
		)
		(fp_poly
			(pts
				(xy -0.508 0.2794) (xy -0.508 0.2286) (xy -0.635 0.2286) (xy -0.635 -0.254) (xy -0.5334 -0.254)
				(xy -0.5334 -0.2794) (xy 0.5334 -0.2794) (xy 0.5334 -0.254) (xy 0.635 -0.254) (xy 0.635 0.254) (xy 0.5334 0.254)
				(xy 0.5334 0.2794)
			)
			(stroke
				(width 0)
				(type default)
			)
			(fill no)
			(layer "F.CrtYd")
		)
		(pad "1" smd rect
			(at 0.40005 0 180)
			(size 0.4572 0.508)
			(layers "F.Cu" "F.Mask" "F.Paste")
			(net "GND")
		)
		(pad "2" smd rect
			(at -0.40005 0 180)
			(size 0.4572 0.508)
			(layers "F.Cu" "F.Mask" "F.Paste")
			(net "PSU6_PS_ON_N")
		)
	)
	(footprint ""
		(layer "F.Cu")
		(at 68.727066 -350.498664 90)
		(property "Reference" "C63"
			(at 1.177036 -0.368046 90)
			(unlocked yes)
			(layer "F.SilkS")
			(effects
				(font
					(size 0.7874 0.5842)
					(thickness 0.1524)
				)
				(justify left)
			)
		)
		(property "Value" ""
			(at 0 0 90)
			(layer "F.Fab")
			(effects
				(font
					(size 1.27 1.27)
				)
			)
		)
		(duplicate_pad_numbers_are_jumpers no)
		(fp_line
			(start 0.7874 -0.4064)
			(end 0.7874 0.4064)
			(stroke
				(width 0.1524)
				(type default)
			)
			(layer "F.SilkS")
		)
		(fp_line
			(start -0.7874 -0.4064)
			(end 0.7874 -0.4064)
			(stroke
				(width 0.1524)
				(type default)
			)
			(layer "F.SilkS")
		)
		(fp_line
			(start 0 0.381)
			(end 0 -0.381)
			(stroke
				(width 0.1524)
				(type default)
			)
			(layer "F.SilkS")
		)
		(fp_line
			(start 0.7874 0.4064)
			(end -0.7874 0.4064)
			(stroke
				(width 0.1524)
				(type default)
			)
			(layer "F.SilkS")
		)
		(fp_line
			(start -0.7874 0.4064)
			(end -0.7874 -0.4064)
			(stroke
				(width 0.1524)
				(type default)
			)
			(layer "F.SilkS")
		)
		(fp_poly
			(pts
				(xy -0.5334 0.254) (xy -0.635 0.254) (xy -0.635 0.2286) (xy -0.635 -0.254) (xy -0.5334 -0.254) (xy -0.5334 -0.2794)
				(xy 0.5334 -0.2794) (xy 0.5334 -0.254) (xy 0.635 -0.254) (xy 0.635 0.254) (xy 0.5334 0.254) (xy 0.5334 0.2794)
				(xy -0.508 0.2794) (xy -0.5334 0.2794)
			)
			(stroke
				(width 0)
				(type default)
			)
			(fill no)
			(layer "F.CrtYd")
		)
		(pad "1" smd rect
			(at 0.40005 0 90)
			(size 0.4572 0.508)
			(layers "F.Cu" "F.Mask" "F.Paste")
			(net "P12V")
		)
		(pad "2" smd rect
			(at -0.40005 0 90)
			(size 0.4572 0.508)
			(layers "F.Cu" "F.Mask" "F.Paste")
			(net "GND")
		)
	)
	(footprint ""
		(layer "F.Cu")
		(at 40.959024 -105.82148 -90)
		(property "Reference" "R8"
			(at 0.823722 -2.429256 90)
			(unlocked yes)
			(layer "F.SilkS")
			(effects
				(font
					(size 0.7874 0.5842)
					(thickness 0.1524)
				)
				(justify left)
			)
		)
		(property "Value" ""
			(at 0 0 270)
			(layer "F.Fab")
			(effects
				(font
					(size 1.27 1.27)
				)
			)
		)
		(duplicate_pad_numbers_are_jumpers no)
		(fp_line
			(start -0.7874 0.4064)
			(end -0.7874 -0.4064)
			(stroke
				(width 0.1524)
				(type default)
			)
			(layer "F.SilkS")
		)
		(fp_line
			(start 0.7874 0.4064)
			(end -0.7874 0.4064)
			(stroke
				(width 0.1524)
				(type default)
			)
			(layer "F.SilkS")
		)
		(fp_line
			(start -0.7874 -0.4064)
			(end 0.7874 -0.4064)
			(stroke
				(width 0.1524)
				(type default)
			)
			(layer "F.SilkS")
		)
		(fp_line
			(start 0.7874 -0.4064)
			(end 0.7874 0.4064)
			(stroke
				(width 0.1524)
				(type default)
			)
			(layer "F.SilkS")
		)
		(fp_poly
			(pts
				(xy -0.508 0.2794) (xy -0.508 0.2286) (xy -0.635 0.2286) (xy -0.635 -0.254) (xy -0.5334 -0.254)
				(xy -0.5334 -0.2794) (xy 0.5334 -0.2794) (xy 0.5334 -0.254) (xy 0.635 -0.254) (xy 0.635 0.254) (xy 0.5334 0.254)
				(xy 0.5334 0.2794)
			)
			(stroke
				(width 0)
				(type default)
			)
			(fill no)
			(layer "F.CrtYd")
		)
		(pad "1" smd rect
			(at 0.40005 0 270)
			(size 0.4572 0.508)
			(layers "F.Cu" "F.Mask" "F.Paste")
			(net "PSU2_AD0")
		)
		(pad "2" smd rect
			(at -0.40005 0 270)
			(size 0.4572 0.508)
			(layers "F.Cu" "F.Mask" "F.Paste")
			(net "GND")
		)
	)
	(footprint ""
		(layer "F.Cu")
		(at 27.243786 -285.030164)
		(property "Reference" "R20"
			(at -3.418332 0.009144 0)
			(unlocked yes)
			(layer "F.SilkS")
			(effects
				(font
					(size 0.7874 0.5842)
					(thickness 0.1524)
				)
				(justify left)
			)
		)
		(property "Value" ""
			(at 0 0 0)
			(layer "F.Fab")
			(effects
				(font
					(size 1.27 1.27)
				)
			)
		)
		(duplicate_pad_numbers_are_jumpers no)
		(fp_line
			(start -0.7874 -0.4064)
			(end 0.7874 -0.4064)
			(stroke
				(width 0.1524)
				(type default)
			)
			(layer "F.SilkS")
		)
		(fp_line
			(start -0.7874 0.4064)
			(end -0.7874 -0.4064)
			(stroke
				(width 0.1524)
				(type default)
			)
			(layer "F.SilkS")
		)
		(fp_line
			(start 0.7874 -0.4064)
			(end 0.7874 0.4064)
			(stroke
				(width 0.1524)
				(type default)
			)
			(layer "F.SilkS")
		)
		(fp_line
			(start 0.7874 0.4064)
			(end -0.7874 0.4064)
			(stroke
				(width 0.1524)
				(type default)
			)
			(layer "F.SilkS")
		)
		(fp_poly
			(pts
				(xy -0.508 0.2794) (xy -0.508 0.2286) (xy -0.635 0.2286) (xy -0.635 -0.254) (xy -0.5334 -0.254)
				(xy -0.5334 -0.2794) (xy 0.5334 -0.2794) (xy 0.5334 -0.254) (xy 0.635 -0.254) (xy 0.635 0.254) (xy 0.5334 0.254)
				(xy 0.5334 0.2794)
			)
			(stroke
				(width 0)
				(type default)
			)
			(fill no)
			(layer "F.CrtYd")
		)
		(pad "1" smd rect
			(at 0.40005 0)
			(size 0.4572 0.508)
			(layers "F.Cu" "F.Mask" "F.Paste")
			(net "PSU4_REMOTE_N")
		)
		(pad "2" smd rect
			(at -0.40005 0)
			(size 0.4572 0.508)
			(layers "F.Cu" "F.Mask" "F.Paste")
			(net "GND")
		)
	)
	(footprint ""
		(layer "F.Cu")
		(at 40.11422 -371.513354 180)
		(property "Reference" "R27"
			(at -1.756918 -0.348742 0)
			(unlocked yes)
			(layer "F.SilkS")
			(effects
				(font
					(size 0.7874 0.5842)
					(thickness 0.1524)
				)
				(justify left)
			)
		)
		(property "Value" ""
			(at 0 0 180)
			(layer "F.Fab")
			(effects
				(font
					(size 1.27 1.27)
				)
			)
		)
		(duplicate_pad_numbers_are_jumpers no)
		(fp_line
			(start 0.7874 0.4064)
			(end -0.7874 0.4064)
			(stroke
				(width 0.1524)
				(type default)
			)
			(layer "F.SilkS")
		)
		(fp_line
			(start 0.7874 -0.4064)
			(end 0.7874 0.4064)
			(stroke
				(width 0.1524)
				(type default)
			)
			(layer "F.SilkS")
		)
		(fp_line
			(start -0.7874 0.4064)
			(end -0.7874 -0.4064)
			(stroke
				(width 0.1524)
				(type default)
			)
			(layer "F.SilkS")
		)
		(fp_line
			(start -0.7874 -0.4064)
			(end 0.7874 -0.4064)
			(stroke
				(width 0.1524)
				(type default)
			)
			(layer "F.SilkS")
		)
		(fp_poly
			(pts
				(xy -0.508 0.2794) (xy -0.508 0.2286) (xy -0.635 0.2286) (xy -0.635 -0.254) (xy -0.5334 -0.254)
				(xy -0.5334 -0.2794) (xy 0.5334 -0.2794) (xy 0.5334 -0.254) (xy 0.635 -0.254) (xy 0.635 0.254) (xy 0.5334 0.254)
				(xy 0.5334 0.2794)
			)
			(stroke
				(width 0)
				(type default)
			)
			(fill no)
			(layer "F.CrtYd")
		)
		(pad "1" smd rect
			(at 0.40005 0 180)
			(size 0.4572 0.508)
			(layers "F.Cu" "F.Mask" "F.Paste")
			(net "PSU5_AD0")
		)
		(pad "2" smd rect
			(at -0.40005 0 180)
			(size 0.4572 0.508)
			(layers "F.Cu" "F.Mask" "F.Paste")
			(net "GND")
		)
	)
)
